G04 ================== begin FILE IDENTIFICATION RECORD ==================*
G04 Layout Name:  13919-sa.brd*
G04 Film Name:    P_OUTLINE*
G04 File Format:  Gerber RS274X*
G04 File Origin:  Cadence Allegro 16.5-S039*
G04 Origin Date:  Fri Nov 22 15:26:56 2013*
G04 *
G04 Layer:  BOARD GEOMETRY/PANEL_OUTLINE*
G04 *
G04 Offset:    (0.00 0.00)*
G04 Mirror:    No*
G04 Mode:      Positive*
G04 Rotation:  0*
G04 FullContactRelief:  No*
G04 UndefLineWidth:     6.00*
G04 ================== end FILE IDENTIFICATION RECORD ====================*
%FSLAX35Y35*MOIN*%
%IR0*IPPOS*OFA0.00000B0.00000*MIA0B0*SFA1.00000B1.00000*%
%ADD10C,.006*%
G75*
%LPD*%
G75*
G54D10*
G01X-20271Y15000D02*
Y676339D01*
G01Y15000D02*
G03X-5271Y0I15000J0D01*
G01Y691339D02*
G03X-20271Y676339I0J-15000D01*
G01X0Y37795D02*
G03X3937Y33858I3937J0D01*
G01X21063Y29921D02*
G03X17126Y33858I-3937J0D01*
G01X3937D02*
X17126D01*
G01X299409Y0D02*
X23031D01*
G01X21063Y1969D02*
X23031Y0D01*
G01X21063Y1969D02*
Y29921D01*
G01X0Y102756D02*
Y37795D01*
G01D02*
G03X-7874I-3937J0D01*
G01X3937Y25984D02*
X13189D01*
G01X-7874Y37795D02*
G03X3937Y25984I11811J0D01*
G01X13189Y0D02*
X-5271D01*
G01X13189Y25984D02*
Y0D01*
G01X3937Y106693D02*
G03X0Y102756I0J-3937D01*
G01X-7874Y68504D02*
G03X0I3937J0D01*
G01X-7874D02*
Y122737D01*
G01X0Y118504D02*
G03X3937Y114567I3937J0D01*
G01Y157382D02*
G03X0Y153445I0J-3937D01*
G01X17126Y157382D02*
G03X21063Y161319I0J3937D01*
G01X0Y118504D02*
Y153445D01*
G01X21063Y219292D02*
Y161319D01*
G01D02*
Y187402D01*
G01X143701Y114567D02*
X3937D01*
G01Y157382D02*
X17126D01*
G01X3937Y106693D02*
X143701D01*
G01X-7874Y153445D02*
Y157382D01*
G01Y153445D02*
G03X0I3937J0D01*
G01Y122737D02*
G03X-7874I-3937J0D01*
G01X-10433Y161070D02*
G03X-7874Y157382I3937J0D01*
G01X-10433Y265210D02*
Y161070D01*
G01X51378Y181496D02*
G03X47441Y177559I0J-3937D01*
G01Y165748D02*
G03X51378Y161811I3937J0D01*
G01X47441Y165748D02*
Y177559D01*
G01X23031Y221260D02*
X21063Y219292D01*
G01X23031Y221260D02*
X63189D01*
G01X0Y272835D02*
G03X3937Y268898I3937J0D01*
G01X21063Y264961D02*
G03X17126Y268898I-3937J0D01*
G01X3937D02*
X17126D01*
G01X299409Y235040D02*
X23031D01*
G01X21063Y237008D02*
X23031Y235040D01*
G01X21063Y237008D02*
Y264961D01*
G01X0Y337796D02*
Y272835D01*
G01D02*
G03X-7874I-3937J0D01*
G01Y268898D02*
G03X-10433Y265210I1378J-3688D01*
G01X-7874Y268898D02*
Y272835D01*
G01X3937Y341733D02*
G03X0Y337796I0J-3937D01*
G01X3937Y341733D02*
X143701D01*
G01X-7874Y303543D02*
Y357781D01*
G01Y303544D02*
G03X0I3937J0D01*
G01X47441Y400788D02*
G03X51378Y396851I3937J0D01*
G01X47441Y400788D02*
Y412599D01*
G01X0Y353544D02*
G03X3937Y349607I3937J0D01*
G01Y392422D02*
G03X0Y388485I0J-3937D01*
G01X17126Y392422D02*
G03X21063Y396359I0J3937D01*
G01X0Y353544D02*
Y388485D01*
G01X21063Y454331D02*
Y396359D01*
G01D02*
Y422441D01*
G01X143701Y349607D02*
X3937D01*
G01Y392422D02*
X17126D01*
G01X-7874Y388480D02*
Y392422D01*
G01Y388485D02*
G03X0I3937J0D01*
G01Y357776D02*
G03X-7874I-3937J0D01*
G01X-10433Y396110D02*
G03X-7874Y392422I3937J0D01*
G01X-10433Y500250D02*
Y396110D01*
G01X51378Y416536D02*
G03X47441Y412599I0J-3937D01*
G01X23031Y456300D02*
X21063Y454331D01*
G01X23031Y456300D02*
X63189D01*
G01X0Y507874D02*
G03X3937Y503937I3937J0D01*
G01X21063Y500000D02*
G03X17126Y503937I-3937J0D01*
G01X3937D02*
X17126D01*
G01X299409Y470079D02*
X23031D01*
G01X21063Y472048D02*
X23031Y470079D01*
G01X21063Y472048D02*
Y500000D01*
G01X0Y572835D02*
Y507874D01*
G01D02*
G03X-7874I-3937J0D01*
G01Y503937D02*
Y507880D01*
G01Y503937D02*
G03X-10433Y500250I1378J-3688D01*
G01X3937Y576772D02*
G03X0Y572835I0J-3937D01*
G01X3937Y576772D02*
X143701D01*
G01X0Y588583D02*
G03X3937Y584646I3937J0D01*
G01X0Y588583D02*
Y623524D01*
G01X143701Y584646D02*
X3937D01*
G01X-7874Y538578D02*
Y592823D01*
G01Y538583D02*
G03X0I3937J0D01*
G01X51378Y651576D02*
G03X47441Y647639I0J-3937D01*
G01Y635828D02*
G03X51378Y631891I3937J0D01*
G01X47441Y635828D02*
Y647639D01*
G01X3937Y627461D02*
G03X0Y623524I0J-3937D01*
G01X17126Y627461D02*
G03X21063Y631398I0J3937D01*
G01Y689371D02*
Y631398D01*
G01D02*
Y657481D01*
G01X3937Y627461D02*
X17126D01*
G01X1830Y651994D02*
G03I-4292J0D01*
G01X-7874Y623517D02*
Y623536D01*
G01X13189Y691339D02*
Y635335D01*
G01X3937D02*
X13189D01*
G01X3937D02*
G03X-7874Y623524I0J-11811D01*
G01D02*
G03X0I3937J0D01*
G01Y592816D02*
G03X-7874I-3937J0D01*
G01X23031Y691339D02*
X21063Y689371D01*
G01X23031Y691339D02*
X63189D01*
G01X13189D02*
X-5271D01*
G01X63189Y161811D02*
G03X67126Y165748I0J3937D01*
G01X73425D02*
G03X77362Y161811I3937J0D01*
G01X89173D02*
G03X93110Y165748I0J3937D01*
G01X99409D02*
G03X103346Y161811I3937J0D01*
G01X63189D02*
X51378D01*
G01X89173D02*
X77362D01*
G01X115157D02*
X103346D01*
G01X89173Y114567D02*
G03Y106693I0J-3937D01*
G01X58465D02*
G03Y114567I0J3937D01*
G01X67126Y177559D02*
G03X63189Y181496I-3937J0D01*
G01X77362D02*
G03X73425Y177559I0J-3937D01*
G01X93110D02*
G03X89173Y181496I-3937J0D01*
G01X103346D02*
G03X99409Y177559I0J-3937D01*
G01X67126D02*
Y165748D01*
G01X73425D02*
Y177559D01*
G01X93110D02*
Y165748D01*
G01X99409D02*
Y177559D01*
G01X103346Y181496D02*
X115157D01*
G01X77362D02*
X89173D01*
G01X51378D02*
X63189D01*
G01X65157Y191930D02*
G03X72638I3740J0D01*
G01X65157Y219292D02*
Y191930D01*
G01X74606Y221260D02*
X72638Y219292D01*
G01D02*
Y191930D01*
G01X65157Y219292D02*
X63189Y221260D01*
G01X74606D02*
X350984D01*
G01X89173Y349607D02*
G03Y341733I0J-3937D01*
G01X58465D02*
G03Y349607I0J3937D01*
G01X63189Y396851D02*
G03X67126Y400788I0J3937D01*
G01X73425D02*
G03X77362Y396851I3937J0D01*
G01X89173D02*
G03X93110Y400788I0J3937D01*
G01X99409D02*
G03X103346Y396851I3937J0D01*
G01X67126Y412599D02*
Y400788D01*
G01X73425D02*
Y412599D01*
G01X93110D02*
Y400788D01*
G01X99409D02*
Y412599D01*
G01X63189Y396851D02*
X51378D01*
G01X89173D02*
X77362D01*
G01X115157D02*
X103346D01*
G01X67126Y412599D02*
G03X63189Y416536I-3937J0D01*
G01X77362D02*
G03X73425Y412599I0J-3937D01*
G01X93110D02*
G03X89173Y416536I-3937J0D01*
G01X103346D02*
G03X99409Y412599I0J-3937D01*
G01X103346Y416536D02*
X115157D01*
G01X77362D02*
X89173D01*
G01X51378D02*
X63189D01*
G01X65157Y426969D02*
G03X72638I3740J0D01*
G01X65157Y454331D02*
Y426969D01*
G01X74606Y456300D02*
X72638Y454331D01*
G01D02*
Y426969D01*
G01X65157Y454331D02*
X63189Y456300D01*
G01X74606D02*
X350984D01*
G01X89173Y584646D02*
G03Y576772I0J-3937D01*
G01X58465D02*
G03Y584646I0J3937D01*
G01X67126Y647639D02*
G03X63189Y651576I-3937J0D01*
G01Y631891D02*
G03X67126Y635828I0J3937D01*
G01X73425D02*
G03X77362Y631891I3937J0D01*
G01Y651576D02*
G03X73425Y647639I0J-3937D01*
G01X93110D02*
G03X89173Y651576I-3937J0D01*
G01Y631891D02*
G03X93110Y635828I0J3937D01*
G01X103346Y651576D02*
G03X99409Y647639I0J-3937D01*
G01Y635828D02*
G03X103346Y631891I3937J0D01*
G01X67126Y647639D02*
Y635828D01*
G01X73425D02*
Y647639D01*
G01X93110D02*
Y635828D01*
G01X99409D02*
Y647639D01*
G01X63189Y631891D02*
X51378D01*
G01X89173D02*
X77362D01*
G01X115157D02*
X103346D01*
G01Y651576D02*
X115157D01*
G01X77362D02*
X89173D01*
G01X51378D02*
X63189D01*
G01X65157Y662009D02*
G03X72638I3740J0D01*
G01X65157Y689371D02*
Y662009D01*
G01X74606Y691339D02*
X72638Y689371D01*
G01D02*
Y662009D01*
G01X65157Y689371D02*
X63189Y691339D01*
G01X74606D02*
X350984D01*
G01X147638Y102756D02*
G03X151575Y98819I3937J0D01*
G01X147638Y102756D02*
G03X143701Y106693I-3937J0D01*
G01X147638Y102756D02*
G03X151575Y98819I3937J0D01*
G01X147638Y102756D02*
G03X143701Y106693I-3937J0D01*
G01X147638Y102756D02*
G03X151575Y98819I3937J0D01*
G01X147638Y102756D02*
G03X143701Y106693I-3937J0D01*
G01X151575Y98819D02*
X222441D01*
G01X115157Y161811D02*
G03X119094Y165748I0J3937D01*
G01X151575Y122441D02*
G03X147638Y118504I0J-3937D01*
G01X143701Y114567D02*
G03X147638Y118504I0J3937D01*
G01X143701Y114567D02*
X112205D01*
G01X143701D02*
G03X147638Y118504I0J3937D01*
G01X151575Y122441D02*
G03X147638Y118504I0J-3937D01*
G01X151575Y122441D02*
G03X147638Y118504I0J-3937D01*
G01X143701Y114567D02*
G03X147638Y118504I0J3937D01*
G01X222441Y122441D02*
X151575D01*
G01X143701Y106693D02*
X112205D01*
G01X119094Y177559D02*
G03X115157Y181496I-3937J0D01*
G01X119094Y177559D02*
Y165748D01*
G01X147638Y337796D02*
G03X151575Y333859I3937J0D01*
G01X147638Y337796D02*
G03X143701Y341733I-3937J0D01*
G01D02*
X112205D01*
G01X147638Y337796D02*
G03X151575Y333859I3937J0D01*
G01X147638Y337796D02*
G03X143701Y341733I-3937J0D01*
G01X147638Y337796D02*
G03X151575Y333859I3937J0D01*
G01X147638Y337796D02*
G03X143701Y341733I-3937J0D01*
G01X151575Y333859D02*
X222441D01*
G01X115157Y396851D02*
G03X119094Y400788I0J3937D01*
G01Y412599D02*
Y400788D01*
G01X151575Y357481D02*
G03X147638Y353544I0J-3937D01*
G01X143701Y349607D02*
G03X147638Y353544I0J3937D01*
G01X143701Y349607D02*
X112205D01*
G01X143701D02*
G03X147638Y353544I0J3937D01*
G01X151575Y357481D02*
G03X147638Y353544I0J-3937D01*
G01X151575Y357481D02*
G03X147638Y353544I0J-3937D01*
G01X143701Y349607D02*
G03X147638Y353544I0J3937D01*
G01X222441Y357481D02*
X151575D01*
G01X119094Y412599D02*
G03X115157Y416536I-3937J0D01*
G01X147638Y572835D02*
G03X151575Y568898I3937J0D01*
G01X147638Y572835D02*
G03X143701Y576772I-3937J0D01*
G01D02*
X112205D01*
G01X147638Y572835D02*
G03X151575Y568898I3937J0D01*
G01X147638Y572835D02*
G03X143701Y576772I-3937J0D01*
G01X147638Y572835D02*
G03X151575Y568898I3937J0D01*
G01X147638Y572835D02*
G03X143701Y576772I-3937J0D01*
G01X151575Y568898D02*
X222441D01*
G01X151575Y592520D02*
G03X147638Y588583I0J-3937D01*
G01X143701Y584646D02*
G03X147638Y588583I0J3937D01*
G01X143701Y584646D02*
X112205D01*
G01X143701D02*
G03X147638Y588583I0J3937D01*
G01X151575Y592520D02*
G03X147638Y588583I0J-3937D01*
G01X151575Y592520D02*
G03X147638Y588583I0J-3937D01*
G01X143701Y584646D02*
G03X147638Y588583I0J3937D01*
G01X119094Y647639D02*
G03X115157Y651576I-3937J0D01*
G01Y631891D02*
G03X119094Y635828I0J3937D01*
G01Y647639D02*
Y635828D01*
G01X222441Y592520D02*
X151575D01*
G01X222441Y98819D02*
G03X226378Y102756I0J3937D01*
G01X230315Y106693D02*
G03X226378Y102756I0J-3937D01*
G01X230315Y106693D02*
G03X226378Y102756I0J-3937D01*
G01X222441Y98819D02*
G03X226378Y102756I0J3937D01*
G01X222441Y98819D02*
G03X226378Y102756I0J3937D01*
G01X230315Y106693D02*
G03X226378Y102756I0J-3937D01*
G01Y118504D02*
G03X222441Y122441I-3937J0D01*
G01X226378Y118504D02*
G03X230315Y114567I3937J0D01*
G01D02*
X261811D01*
G01X226378Y118504D02*
G03X222441Y122441I-3937J0D01*
G01X226378Y118504D02*
G03X230315Y114567I3937J0D01*
G01X226378Y118504D02*
G03X222441Y122441I-3937J0D01*
G01X226378Y118504D02*
G03X230315Y114567I3937J0D01*
G01X370079D02*
X230315D01*
G01Y106693D02*
X261811D01*
G01X230315D02*
X370079D01*
G01X222441Y333859D02*
G03X226378Y337796I0J3937D01*
G01X230315Y341733D02*
G03X226378Y337796I0J-3937D01*
G01X230315Y341733D02*
X261811D01*
G01X230315D02*
G03X226378Y337796I0J-3937D01*
G01X222441Y333859D02*
G03X226378Y337796I0J3937D01*
G01X222441Y333859D02*
G03X226378Y337796I0J3937D01*
G01X230315Y341733D02*
G03X226378Y337796I0J-3937D01*
G01X230315Y341733D02*
X370079D01*
G01X226378Y353544D02*
G03X222441Y357481I-3937J0D01*
G01X226378Y353544D02*
G03X230315Y349607I3937J0D01*
G01D02*
X261811D01*
G01X226378Y353544D02*
G03X222441Y357481I-3937J0D01*
G01X226378Y353544D02*
G03X230315Y349607I3937J0D01*
G01X226378Y353544D02*
G03X222441Y357481I-3937J0D01*
G01X226378Y353544D02*
G03X230315Y349607I3937J0D01*
G01X370079D02*
X230315D01*
G01X222441Y568898D02*
G03X226378Y572835I0J3937D01*
G01X230315Y576772D02*
G03X226378Y572835I0J-3937D01*
G01X230315Y576772D02*
X261811D01*
G01X230315D02*
G03X226378Y572835I0J-3937D01*
G01X222441Y568898D02*
G03X226378Y572835I0J3937D01*
G01X222441Y568898D02*
G03X226378Y572835I0J3937D01*
G01X230315Y576772D02*
G03X226378Y572835I0J-3937D01*
G01X230315Y576772D02*
X370079D01*
G01X226378Y588583D02*
G03X222441Y592520I-3937J0D01*
G01X226378Y588583D02*
G03X230315Y584646I3937J0D01*
G01D02*
X261811D01*
G01X226378Y588583D02*
G03X222441Y592520I-3937J0D01*
G01X226378Y588583D02*
G03X230315Y584646I3937J0D01*
G01X226378Y588583D02*
G03X222441Y592520I-3937J0D01*
G01X226378Y588583D02*
G03X230315Y584646I3937J0D01*
G01X370079D02*
X230315D01*
G01X280906Y43701D02*
G03X284843Y39764I3937J0D01*
G01X270669D02*
G03X274606Y43701I0J3937D01*
G01X254921D02*
G03X258858Y39764I3937J0D01*
G01X270669D02*
X258858D01*
G01X296654D02*
X284843D01*
G01Y59449D02*
G03X280906Y55512I0J-3937D01*
G01X258858Y59449D02*
G03X254921Y55512I0J-3937D01*
G01X274606D02*
G03X270669Y59449I-3937J0D01*
G01X280906Y43701D02*
Y55512D01*
G01X274606D02*
Y43701D01*
G01X254921D02*
Y55512D01*
G01X284843Y59449D02*
X296654D01*
G01X258858D02*
X270669D01*
G01X284843Y106693D02*
G03Y114567I0J3937D01*
G01X280906Y278741D02*
G03X284843Y274804I3937J0D01*
G01X270669D02*
G03X274606Y278741I0J3937D01*
G01X254921D02*
G03X258858Y274804I3937J0D01*
G01X280906Y278741D02*
Y290552D01*
G01X274606D02*
Y278741D01*
G01X254921D02*
Y290552D01*
G01X270669Y274804D02*
X258858D01*
G01X296654D02*
X284843D01*
G01Y294489D02*
G03X280906Y290552I0J-3937D01*
G01X258858Y294489D02*
G03X254921Y290552I0J-3937D01*
G01X274606D02*
G03X270669Y294489I-3937J0D01*
G01X284843D02*
X296654D01*
G01X258858D02*
X270669D01*
G01X284843Y341733D02*
G03Y349607I0J3937D01*
G01X280906Y513780D02*
G03X284843Y509843I3937J0D01*
G01Y529528D02*
G03X280906Y525591I0J-3937D01*
G01X270669Y509843D02*
G03X274606Y513780I0J3937D01*
G01X254921D02*
G03X258858Y509843I3937J0D01*
G01Y529528D02*
G03X254921Y525591I0J-3937D01*
G01X274606D02*
G03X270669Y529528I-3937J0D01*
G01X280906Y513780D02*
Y525591D01*
G01X274606D02*
Y513780D01*
G01X254921D02*
Y525591D01*
G01X284843Y529528D02*
X296654D01*
G01X258858D02*
X270669D01*
G01Y509843D02*
X258858D01*
G01X296654D02*
X284843D01*
G01Y576772D02*
G03Y584646I0J3937D01*
G01X322638Y39764D02*
G03X326575Y43701I0J3937D01*
G01X306890D02*
G03X310827Y39764I3937J0D01*
G01X296654D02*
G03X300591Y43701I0J3937D01*
G01X322638Y39764D02*
X310827D01*
G01X308858Y29331D02*
G03X301378I-3740J0D01*
G01X350984Y0D02*
X352953Y1969D01*
G01X308858D02*
Y29331D01*
G01X299409Y0D02*
X301378Y1969D01*
G01D02*
Y29331D01*
G01X308858Y1969D02*
X310827Y0D01*
G01X350984D02*
X310827D01*
G01Y59449D02*
G03X306890Y55512I0J-3937D01*
G01X326575D02*
G03X322638Y59449I-3937J0D01*
G01X300591Y55512D02*
G03X296654Y59449I-3937J0D01*
G01X326575Y55512D02*
Y43701D01*
G01X306890D02*
Y55512D01*
G01X300591D02*
Y43701D01*
G01X310827Y59449D02*
X322638D01*
G01X315551Y114567D02*
G03Y106693I0J-3937D01*
G01X352953Y219292D02*
X350984Y221260D01*
G01X322638Y274804D02*
G03X326575Y278741I0J3937D01*
G01X306890D02*
G03X310827Y274804I3937J0D01*
G01X296654D02*
G03X300591Y278741I0J3937D01*
G01X326575Y290552D02*
Y278741D01*
G01X306890D02*
Y290552D01*
G01X300591D02*
Y278741D01*
G01X322638Y274804D02*
X310827D01*
G01X308858Y264370D02*
G03X301378I-3740J0D01*
G01X350984Y235040D02*
X352953Y237008D01*
G01X308858D02*
Y264370D01*
G01X299409Y235040D02*
X301378Y237008D01*
G01D02*
Y264370D01*
G01X308858Y237008D02*
X310827Y235040D01*
G01X350984D02*
X310827D01*
G01Y294489D02*
G03X306890Y290552I0J-3937D01*
G01X326575D02*
G03X322638Y294489I-3937J0D01*
G01X300591Y290552D02*
G03X296654Y294489I-3937J0D01*
G01X310827D02*
X322638D01*
G01X315551Y349607D02*
G03Y341733I0J-3937D01*
G01X352953Y454331D02*
X350984Y456300D01*
G01X322638Y509843D02*
G03X326575Y513780I0J3937D01*
G01X306890D02*
G03X310827Y509843I3937J0D01*
G01Y529528D02*
G03X306890Y525591I0J-3937D01*
G01X326575D02*
G03X322638Y529528I-3937J0D01*
G01X300591Y525591D02*
G03X296654Y529528I-3937J0D01*
G01Y509843D02*
G03X300591Y513780I0J3937D01*
G01X326575Y525591D02*
Y513780D01*
G01X306890D02*
Y525591D01*
G01X300591D02*
Y513780D01*
G01X310827Y529528D02*
X322638D01*
G01Y509843D02*
X310827D01*
G01X308858Y499410D02*
G03X301378I-3740J0D01*
G01X350984Y470079D02*
X352953Y472048D01*
G01X308858D02*
Y499410D01*
G01X299409Y470079D02*
X301378Y472048D01*
G01D02*
Y499410D01*
G01X308858Y472048D02*
X310827Y470079D01*
G01X350984D02*
X310827D01*
G01X315551Y584646D02*
G03Y576772I0J-3937D01*
G01X352953Y689371D02*
X350984Y691339D01*
G01X381890Y37795D02*
G03X385827Y33858I3937J0D01*
G01X402953Y29921D02*
G03X399016Y33858I-3937J0D01*
G01X385827D02*
X399016D01*
G01X681299Y0D02*
X404921D01*
G01X402953Y1969D02*
X404921Y0D01*
G01X402953Y1969D02*
Y29921D01*
G01X381890Y102756D02*
Y37795D01*
G01X352953Y1969D02*
Y59941D01*
G01D02*
Y33858D01*
G01X385827Y106693D02*
G03X381890Y102756I0J-3937D01*
G01X374016D02*
G03X370079Y106693I-3937J0D01*
G01Y63878D02*
G03X374016Y67815I0J3937D01*
G01X356890Y63878D02*
G03X352953Y59941I0J-3937D01*
G01X374016Y102756D02*
Y67815D01*
G01X370079Y63878D02*
X356890D01*
G01X374016Y98524D02*
G03X381890I3937J0D01*
G01Y67815D02*
G03X374016I-3937J0D01*
G01X385827Y106693D02*
X525591D01*
G01X370079Y114567D02*
G03X374016Y118504I0J3937D01*
G01D02*
Y183465D01*
G01X381890Y118504D02*
G03X385827Y114567I3937J0D01*
G01Y157382D02*
G03X381890Y153445I0J-3937D01*
G01X399016Y157382D02*
G03X402953Y161319I0J3937D01*
G01X381890Y118504D02*
Y153445D01*
G01X402953Y219292D02*
Y161319D01*
G01D02*
Y187402D01*
G01X525591Y114567D02*
X385827D01*
G01Y157382D02*
X399016D01*
G01X374016Y153445D02*
G03X381890I3937J0D01*
G01Y122737D02*
G03X374016I-3937J0D01*
G01Y183465D02*
G03X370079Y187402I-3937J0D01*
G01X352953Y191339D02*
G03X356890Y187402I3937J0D01*
G01X370079D02*
X356890D01*
G01X352953Y219292D02*
Y191339D01*
G01X404921Y221260D02*
X402953Y219292D01*
G01X404921Y221260D02*
X445079D01*
G01X352953Y237008D02*
Y294981D01*
G01D02*
Y268898D01*
G01X381890Y272835D02*
G03X385827Y268898I3937J0D01*
G01X402953Y264961D02*
G03X399016Y268898I-3937J0D01*
G01X385827D02*
X399016D01*
G01X681299Y235040D02*
X404921D01*
G01X402953Y237008D02*
X404921Y235040D01*
G01X402953Y237008D02*
Y264961D01*
G01X381890Y337796D02*
Y272835D01*
G01X374016Y337796D02*
G03X370079Y341733I-3937J0D01*
G01Y298918D02*
G03X374016Y302855I0J3937D01*
G01X356890Y298918D02*
G03X352953Y294981I0J-3937D01*
G01X374016Y337796D02*
Y302855D01*
G01X370079Y298918D02*
X356890D01*
G01X385827Y341733D02*
G03X381890Y337796I0J-3937D01*
G01X385827Y341733D02*
X525591D01*
G01X374016Y333563D02*
G03X381890I3937J0D01*
G01Y302855D02*
G03X374016I-3937J0D01*
G01X381890Y353544D02*
G03X385827Y349607I3937J0D01*
G01Y392422D02*
G03X381890Y388485I0J-3937D01*
G01X399016Y392422D02*
G03X402953Y396359I0J3937D01*
G01X381890Y353544D02*
Y388485D01*
G01X402953Y454331D02*
Y396359D01*
G01D02*
Y422441D01*
G01X525591Y349607D02*
X385827D01*
G01Y392422D02*
X399016D01*
G01X370079Y349607D02*
G03X374016Y353544I0J3937D01*
G01D02*
Y418504D01*
G01Y388485D02*
G03X381890I3937J0D01*
G01Y357776D02*
G03X374016I-3937J0D01*
G01X404921Y456300D02*
X402953Y454331D01*
G01X404921Y456300D02*
X445079D01*
G01X374016Y418504D02*
G03X370079Y422441I-3937J0D01*
G01X352953Y426378D02*
G03X356890Y422441I3937J0D01*
G01X370079D02*
X356890D01*
G01X352953Y454331D02*
Y426378D01*
G01Y472048D02*
Y530020D01*
G01D02*
Y503937D01*
G01X381890Y507874D02*
G03X385827Y503937I3937J0D01*
G01X402953Y500000D02*
G03X399016Y503937I-3937J0D01*
G01X385827D02*
X399016D01*
G01X681299Y470079D02*
X404921D01*
G01X402953Y472048D02*
X404921Y470079D01*
G01X402953Y472048D02*
Y500000D01*
G01X381890Y572835D02*
Y507874D01*
G01X374016Y572835D02*
G03X370079Y576772I-3937J0D01*
G01Y533957D02*
G03X374016Y537894I0J3937D01*
G01X356890Y533957D02*
G03X352953Y530020I0J-3937D01*
G01X374016Y572835D02*
Y537894D01*
G01X370079Y533957D02*
X356890D01*
G01X385827Y576772D02*
G03X381890Y572835I0J-3937D01*
G01X385827Y576772D02*
X525591D01*
G01X381890Y588583D02*
G03X385827Y584646I3937J0D01*
G01X381890Y588583D02*
Y623524D01*
G01X525591Y584646D02*
X385827D01*
G01X370079D02*
G03X374016Y588583I0J3937D01*
G01D02*
Y653544D01*
G01Y568603D02*
G03X381890I3937J0D01*
G01Y537894D02*
G03X374016I-3937J0D01*
G01X385827Y627461D02*
G03X381890Y623524I0J-3937D01*
G01X399016Y627461D02*
G03X402953Y631398I0J3937D01*
G01Y689371D02*
Y631398D01*
G01D02*
Y657481D01*
G01X385827Y627461D02*
X399016D01*
G01X374016Y623524D02*
G03X381890I3937J0D01*
G01Y592816D02*
G03X374016I-3937J0D01*
G01X404921Y691339D02*
X402953Y689371D01*
G01X404921Y691339D02*
X445079D01*
G01X374016Y653544D02*
G03X370079Y657481I-3937J0D01*
G01X352953Y661418D02*
G03X356890Y657481I3937J0D01*
G01X370079D02*
X356890D01*
G01X352953Y689371D02*
Y661418D01*
G01X445079Y161811D02*
G03X449016Y165748I0J3937D01*
G01X429331D02*
G03X433268Y161811I3937J0D01*
G01X455315Y165748D02*
G03X459252Y161811I3937J0D01*
G01X471063D02*
G03X475000Y165748I0J3937D01*
G01X445079Y161811D02*
X433268D01*
G01X471063D02*
X459252D01*
G01X471063Y114567D02*
G03Y106693I0J-3937D01*
G01X440354D02*
G03Y114567I0J3937D01*
G01X433268Y181496D02*
G03X429331Y177559I0J-3937D01*
G01X449016D02*
G03X445079Y181496I-3937J0D01*
G01X459252D02*
G03X455315Y177559I0J-3937D01*
G01X475000D02*
G03X471063Y181496I-3937J0D01*
G01X429331Y165748D02*
Y177559D01*
G01X449016D02*
Y165748D01*
G01X455315D02*
Y177559D01*
G01X459252Y181496D02*
X471063D01*
G01X433268D02*
X445079D01*
G01X447047Y191930D02*
G03X454528I3740J0D01*
G01X447047Y219292D02*
Y191930D01*
G01X456496Y221260D02*
X454528Y219292D01*
G01D02*
Y191930D01*
G01X447047Y219292D02*
X445079Y221260D01*
G01X456496D02*
X732874D01*
G01X471063Y349607D02*
G03Y341733I0J-3937D01*
G01X440354D02*
G03Y349607I0J3937D01*
G01X445079Y396851D02*
G03X449016Y400788I0J3937D01*
G01X429331D02*
G03X433268Y396851I3937J0D01*
G01X455315Y400788D02*
G03X459252Y396851I3937J0D01*
G01X471063D02*
G03X475000Y400788I0J3937D01*
G01X429331D02*
Y412599D01*
G01X449016D02*
Y400788D01*
G01X455315D02*
Y412599D01*
G01X445079Y396851D02*
X433268D01*
G01X471063D02*
X459252D01*
G01X433268Y416536D02*
G03X429331Y412599I0J-3937D01*
G01X449016D02*
G03X445079Y416536I-3937J0D01*
G01X459252D02*
G03X455315Y412599I0J-3937D01*
G01X475000D02*
G03X471063Y416536I-3937J0D01*
G01X459252D02*
X471063D01*
G01X433268D02*
X445079D01*
G01X447047Y426969D02*
G03X454528I3740J0D01*
G01X447047Y454331D02*
Y426969D01*
G01X456496Y456300D02*
X454528Y454331D01*
G01D02*
Y426969D01*
G01X447047Y454331D02*
X445079Y456300D01*
G01X456496D02*
X732874D01*
G01X471063Y584646D02*
G03Y576772I0J-3937D01*
G01X440354D02*
G03Y584646I0J3937D01*
G01X433268Y651576D02*
G03X429331Y647639I0J-3937D01*
G01X449016D02*
G03X445079Y651576I-3937J0D01*
G01Y631891D02*
G03X449016Y635828I0J3937D01*
G01X429331D02*
G03X433268Y631891I3937J0D01*
G01X455315Y635828D02*
G03X459252Y631891I3937J0D01*
G01Y651576D02*
G03X455315Y647639I0J-3937D01*
G01X475000D02*
G03X471063Y651576I-3937J0D01*
G01Y631891D02*
G03X475000Y635828I0J3937D01*
G01X429331D02*
Y647639D01*
G01X449016D02*
Y635828D01*
G01X455315D02*
Y647639D01*
G01X445079Y631891D02*
X433268D01*
G01X471063D02*
X459252D01*
G01Y651576D02*
X471063D01*
G01X433268D02*
X445079D01*
G01X447047Y662009D02*
G03X454528I3740J0D01*
G01X447047Y689371D02*
Y662009D01*
G01X456496Y691339D02*
X454528Y689371D01*
G01D02*
Y662009D01*
G01X447047Y689371D02*
X445079Y691339D01*
G01X456496D02*
X732874D01*
G01X529528Y102756D02*
G03X533465Y98819I3937J0D01*
G01X529528Y102756D02*
G03X525591Y106693I-3937J0D01*
G01X529528Y102756D02*
G03X533465Y98819I3937J0D01*
G01X529528Y102756D02*
G03X525591Y106693I-3937J0D01*
G01X529528Y102756D02*
G03X533465Y98819I3937J0D01*
G01X529528Y102756D02*
G03X525591Y106693I-3937J0D01*
G01X533465Y98819D02*
X604331D01*
G01X525591Y106693D02*
X494094D01*
G01X497047Y161811D02*
G03X500984Y165748I0J3937D01*
G01X481299D02*
G03X485236Y161811I3937J0D01*
G01X497047D02*
X485236D01*
G01X533465Y122441D02*
G03X529528Y118504I0J-3937D01*
G01X525591Y114567D02*
G03X529528Y118504I0J3937D01*
G01X525591Y114567D02*
X494094D01*
G01X525591D02*
G03X529528Y118504I0J3937D01*
G01X533465Y122441D02*
G03X529528Y118504I0J-3937D01*
G01X533465Y122441D02*
G03X529528Y118504I0J-3937D01*
G01X525591Y114567D02*
G03X529528Y118504I0J3937D01*
G01X604331Y122441D02*
X533465D01*
G01X485236Y181496D02*
G03X481299Y177559I0J-3937D01*
G01X500984D02*
G03X497047Y181496I-3937J0D01*
G01X475000Y177559D02*
Y165748D01*
G01X481299D02*
Y177559D01*
G01X500984D02*
Y165748D01*
G01X485236Y181496D02*
X497047D01*
G01X529528Y337796D02*
G03X533465Y333859I3937J0D01*
G01X529528Y337796D02*
G03X525591Y341733I-3937J0D01*
G01D02*
X494094D01*
G01X529528Y337796D02*
G03X533465Y333859I3937J0D01*
G01X529528Y337796D02*
G03X525591Y341733I-3937J0D01*
G01X529528Y337796D02*
G03X533465Y333859I3937J0D01*
G01X529528Y337796D02*
G03X525591Y341733I-3937J0D01*
G01X533465Y333859D02*
X604331D01*
G01X497047Y396851D02*
G03X500984Y400788I0J3937D01*
G01X481299D02*
G03X485236Y396851I3937J0D01*
G01X475000Y412599D02*
Y400788D01*
G01X481299D02*
Y412599D01*
G01X500984D02*
Y400788D01*
G01X497047Y396851D02*
X485236D01*
G01X533465Y357481D02*
G03X529528Y353544I0J-3937D01*
G01X525591Y349607D02*
G03X529528Y353544I0J3937D01*
G01X525591Y349607D02*
X494094D01*
G01X525591D02*
G03X529528Y353544I0J3937D01*
G01X533465Y357481D02*
G03X529528Y353544I0J-3937D01*
G01X533465Y357481D02*
G03X529528Y353544I0J-3937D01*
G01X525591Y349607D02*
G03X529528Y353544I0J3937D01*
G01X604331Y357481D02*
X533465D01*
G01X485236Y416536D02*
G03X481299Y412599I0J-3937D01*
G01X500984D02*
G03X497047Y416536I-3937J0D01*
G01X485236D02*
X497047D01*
G01X529528Y572835D02*
G03X533465Y568898I3937J0D01*
G01X529528Y572835D02*
G03X525591Y576772I-3937J0D01*
G01D02*
X494094D01*
G01X529528Y572835D02*
G03X533465Y568898I3937J0D01*
G01X529528Y572835D02*
G03X525591Y576772I-3937J0D01*
G01X529528Y572835D02*
G03X533465Y568898I3937J0D01*
G01X529528Y572835D02*
G03X525591Y576772I-3937J0D01*
G01X533465Y568898D02*
X604331D01*
G01X533465Y592520D02*
G03X529528Y588583I0J-3937D01*
G01X525591Y584646D02*
G03X529528Y588583I0J3937D01*
G01X525591Y584646D02*
X494094D01*
G01X525591D02*
G03X529528Y588583I0J3937D01*
G01X533465Y592520D02*
G03X529528Y588583I0J-3937D01*
G01X533465Y592520D02*
G03X529528Y588583I0J-3937D01*
G01X525591Y584646D02*
G03X529528Y588583I0J3937D01*
G01X485236Y651576D02*
G03X481299Y647639I0J-3937D01*
G01X500984D02*
G03X497047Y651576I-3937J0D01*
G01Y631891D02*
G03X500984Y635828I0J3937D01*
G01X481299D02*
G03X485236Y631891I3937J0D01*
G01X475000Y647639D02*
Y635828D01*
G01X481299D02*
Y647639D01*
G01X500984D02*
Y635828D01*
G01X497047Y631891D02*
X485236D01*
G01Y651576D02*
X497047D01*
G01X604331Y592520D02*
X533465D01*
G01X652559Y39764D02*
G03X656496Y43701I0J3937D01*
G01X636811D02*
G03X640748Y39764I3937J0D01*
G01X652559D02*
X640748D01*
G01Y59449D02*
G03X636811Y55512I0J-3937D01*
G01X656496D02*
G03X652559Y59449I-3937J0D01*
G01X656496Y55512D02*
Y43701D01*
G01X636811D02*
Y55512D01*
G01X640748Y59449D02*
X652559D01*
G01X604331Y98819D02*
G03X608268Y102756I0J3937D01*
G01X612205Y106693D02*
G03X608268Y102756I0J-3937D01*
G01X612205Y106693D02*
G03X608268Y102756I0J-3937D01*
G01X604331Y98819D02*
G03X608268Y102756I0J3937D01*
G01X604331Y98819D02*
G03X608268Y102756I0J3937D01*
G01X612205Y106693D02*
G03X608268Y102756I0J-3937D01*
G01X612205Y106693D02*
X643701D01*
G01X612205D02*
X751969D01*
G01X608268Y118504D02*
G03X604331Y122441I-3937J0D01*
G01X608268Y118504D02*
G03X612205Y114567I3937J0D01*
G01D02*
X643701D01*
G01X608268Y118504D02*
G03X604331Y122441I-3937J0D01*
G01X608268Y118504D02*
G03X612205Y114567I3937J0D01*
G01X608268Y118504D02*
G03X604331Y122441I-3937J0D01*
G01X608268Y118504D02*
G03X612205Y114567I3937J0D01*
G01X751969D02*
X612205D01*
G01X652559Y274804D02*
G03X656496Y278741I0J3937D01*
G01X636811D02*
G03X640748Y274804I3937J0D01*
G01X656496Y290552D02*
Y278741D01*
G01X636811D02*
Y290552D01*
G01X652559Y274804D02*
X640748D01*
G01Y294489D02*
G03X636811Y290552I0J-3937D01*
G01X656496D02*
G03X652559Y294489I-3937J0D01*
G01X640748D02*
X652559D01*
G01X604331Y333859D02*
G03X608268Y337796I0J3937D01*
G01X612205Y341733D02*
G03X608268Y337796I0J-3937D01*
G01X612205Y341733D02*
X643701D01*
G01X612205D02*
G03X608268Y337796I0J-3937D01*
G01X604331Y333859D02*
G03X608268Y337796I0J3937D01*
G01X604331Y333859D02*
G03X608268Y337796I0J3937D01*
G01X612205Y341733D02*
G03X608268Y337796I0J-3937D01*
G01X612205Y341733D02*
X751969D01*
G01X608268Y353544D02*
G03X604331Y357481I-3937J0D01*
G01X608268Y353544D02*
G03X612205Y349607I3937J0D01*
G01D02*
X643701D01*
G01X608268Y353544D02*
G03X604331Y357481I-3937J0D01*
G01X608268Y353544D02*
G03X612205Y349607I3937J0D01*
G01X608268Y353544D02*
G03X604331Y357481I-3937J0D01*
G01X608268Y353544D02*
G03X612205Y349607I3937J0D01*
G01X751969D02*
X612205D01*
G01X652559Y509843D02*
G03X656496Y513780I0J3937D01*
G01X636811D02*
G03X640748Y509843I3937J0D01*
G01Y529528D02*
G03X636811Y525591I0J-3937D01*
G01X656496D02*
G03X652559Y529528I-3937J0D01*
G01X656496Y525591D02*
Y513780D01*
G01X636811D02*
Y525591D01*
G01X640748Y529528D02*
X652559D01*
G01Y509843D02*
X640748D01*
G01X604331Y568898D02*
G03X608268Y572835I0J3937D01*
G01X612205Y576772D02*
G03X608268Y572835I0J-3937D01*
G01X612205Y576772D02*
X643701D01*
G01X612205D02*
G03X608268Y572835I0J-3937D01*
G01X604331Y568898D02*
G03X608268Y572835I0J3937D01*
G01X604331Y568898D02*
G03X608268Y572835I0J3937D01*
G01X612205Y576772D02*
G03X608268Y572835I0J-3937D01*
G01X612205Y576772D02*
X751969D01*
G01X608268Y588583D02*
G03X604331Y592520I-3937J0D01*
G01X608268Y588583D02*
G03X612205Y584646I3937J0D01*
G01D02*
X643701D01*
G01X608268Y588583D02*
G03X604331Y592520I-3937J0D01*
G01X608268Y588583D02*
G03X612205Y584646I3937J0D01*
G01X608268Y588583D02*
G03X604331Y592520I-3937J0D01*
G01X608268Y588583D02*
G03X612205Y584646I3937J0D01*
G01X751969D02*
X612205D01*
G01X704528Y39764D02*
G03X708465Y43701I0J3937D01*
G01X688780D02*
G03X692717Y39764I3937J0D01*
G01X678543D02*
G03X682480Y43701I0J3937D01*
G01X662795D02*
G03X666732Y39764I3937J0D01*
G01X678543D02*
X666732D01*
G01X704528D02*
X692717D01*
G01X690748Y29331D02*
G03X683268I-3740J0D01*
G01X690748Y1969D02*
Y29331D01*
G01X681299Y0D02*
X683268Y1969D01*
G01D02*
Y29331D01*
G01X690748Y1969D02*
X692717Y0D01*
G01X732874D02*
X692717D01*
G01Y59449D02*
G03X688780Y55512I0J-3937D01*
G01X708465D02*
G03X704528Y59449I-3937J0D01*
G01X682480Y55512D02*
G03X678543Y59449I-3937J0D01*
G01X666732D02*
G03X662795Y55512I0J-3937D01*
G01X708465D02*
Y43701D01*
G01X688780D02*
Y55512D01*
G01X682480D02*
Y43701D01*
G01X662795D02*
Y55512D01*
G01X692717Y59449D02*
X704528D01*
G01X666732D02*
X678543D01*
G01X697441Y114567D02*
G03Y106693I0J-3937D01*
G01X666732D02*
G03Y114567I0J3937D01*
G01X704528Y274804D02*
G03X708465Y278741I0J3937D01*
G01X688780D02*
G03X692717Y274804I3937J0D01*
G01X678543D02*
G03X682480Y278741I0J3937D01*
G01X662795D02*
G03X666732Y274804I3937J0D01*
G01X708465Y290552D02*
Y278741D01*
G01X688780D02*
Y290552D01*
G01X682480D02*
Y278741D01*
G01X662795D02*
Y290552D01*
G01X678543Y274804D02*
X666732D01*
G01X704528D02*
X692717D01*
G01X690748Y264370D02*
G03X683268I-3740J0D01*
G01X690748Y237008D02*
Y264370D01*
G01X681299Y235040D02*
X683268Y237008D01*
G01D02*
Y264370D01*
G01X690748Y237008D02*
X692717Y235040D01*
G01X732874D02*
X692717D01*
G01Y294489D02*
G03X688780Y290552I0J-3937D01*
G01X708465D02*
G03X704528Y294489I-3937J0D01*
G01X682480Y290552D02*
G03X678543Y294489I-3937J0D01*
G01X666732D02*
G03X662795Y290552I0J-3937D01*
G01X692717Y294489D02*
X704528D01*
G01X666732D02*
X678543D01*
G01X697441Y349607D02*
G03Y341733I0J-3937D01*
G01X666732D02*
G03Y349607I0J3937D01*
G01X704528Y509843D02*
G03X708465Y513780I0J3937D01*
G01X688780D02*
G03X692717Y509843I3937J0D01*
G01Y529528D02*
G03X688780Y525591I0J-3937D01*
G01X708465D02*
G03X704528Y529528I-3937J0D01*
G01X682480Y525591D02*
G03X678543Y529528I-3937J0D01*
G01Y509843D02*
G03X682480Y513780I0J3937D01*
G01X662795D02*
G03X666732Y509843I3937J0D01*
G01Y529528D02*
G03X662795Y525591I0J-3937D01*
G01X708465D02*
Y513780D01*
G01X688780D02*
Y525591D01*
G01X682480D02*
Y513780D01*
G01X662795D02*
Y525591D01*
G01X692717Y529528D02*
X704528D01*
G01X666732D02*
X678543D01*
G01Y509843D02*
X666732D01*
G01X704528D02*
X692717D01*
G01X690748Y499410D02*
G03X683268I-3740J0D01*
G01X690748Y472048D02*
Y499410D01*
G01X681299Y470079D02*
X683268Y472048D01*
G01D02*
Y499410D01*
G01X690748Y472048D02*
X692717Y470079D01*
G01X732874D02*
X692717D01*
G01X697441Y584646D02*
G03Y576772I0J-3937D01*
G01X666732D02*
G03Y584646I0J3937D01*
G01X734843Y1969D02*
Y59941D01*
G01D02*
Y33858D01*
G01X732874Y0D02*
X734843Y1969D01*
G01X762744Y17317D02*
G03I-4292J0D01*
G01X775591Y553149D02*
Y15000D01*
G01X760591Y0D02*
G03X775591Y15000I0J15000D01*
G01X742717Y0D02*
Y56004D01*
G01Y0D02*
X760591D01*
G01X755906Y102756D02*
G03X751969Y106693I-3937J0D01*
G01Y63878D02*
G03X755906Y67815I0J3937D01*
G01X738780Y63878D02*
G03X734843Y59941I0J-3937D01*
G01X755906Y102756D02*
Y67815D01*
G01X751969Y63878D02*
X738780D01*
G01X763780Y152761D02*
Y98517D01*
G01Y67822D02*
Y67803D01*
G01X751969Y56004D02*
X742717D01*
G01X751969D02*
G03X763780Y67815I0J11811D01*
G01D02*
G03X755906I-3937J0D01*
G01Y98524D02*
G03X763780I3937J0D01*
G01X751969Y114567D02*
G03X755906Y118504I0J3937D01*
G01D02*
Y183465D01*
G01X763780Y152756D02*
G03X755906I-3937J0D01*
G01Y183465D02*
G03X751969Y187402I-3937J0D01*
G01X734843Y191339D02*
G03X738780Y187402I3937J0D01*
G01X751969D02*
X738780D01*
G01X734843Y219292D02*
X732874Y221260D01*
G01X734843Y219292D02*
Y191339D01*
G01X755906Y183465D02*
G03X763780I3937J0D01*
G01Y302855D02*
Y183460D01*
G01X734843Y237008D02*
Y294981D01*
G01D02*
Y268898D01*
G01X732874Y235040D02*
X734843Y237008D01*
G01X755906Y337796D02*
G03X751969Y341733I-3937J0D01*
G01Y298918D02*
G03X755906Y302855I0J3937D01*
G01X738780Y298918D02*
G03X734843Y294981I0J-3937D01*
G01X755906Y337796D02*
Y302855D01*
G01X751969Y298918D02*
X738780D01*
G01X763780Y387796D02*
Y333559D01*
G01Y302855D02*
G03X755906I-3937J0D01*
G01Y333563D02*
G03X763780I3937J0D01*
G01X751969Y349607D02*
G03X755906Y353544I0J3937D01*
G01D02*
Y418504D01*
G01X763780Y387796D02*
G03X755906I-3937J0D01*
G01Y418504D02*
G03X751969Y422441I-3937J0D01*
G01X734843Y426378D02*
G03X738780Y422441I3937J0D01*
G01X751969D02*
X738780D01*
G01X734843Y454331D02*
X732874Y456300D01*
G01X734843Y454331D02*
Y426378D01*
G01X763780Y537894D02*
Y418504D01*
G01X755906Y418505D02*
G03X763780I3937J0D01*
G01X734843Y472048D02*
Y530020D01*
G01D02*
Y503937D01*
G01X732874Y470079D02*
X734843Y472048D01*
G01X755906Y572835D02*
G03X751969Y576772I-3937J0D01*
G01Y533957D02*
G03X755906Y537894I0J3937D01*
G01X738780Y533957D02*
G03X734843Y530020I0J-3937D01*
G01X755906Y572835D02*
Y537894D01*
G01X751969Y533957D02*
X738780D01*
G01X751969Y584646D02*
G03X755906Y588583I0J3937D01*
G01D02*
Y653544D01*
G01X775591Y561023D02*
G03Y553149I0J-3937D01*
G01X763780Y537894D02*
G03X755906I-3937J0D01*
G01Y568603D02*
G03X763780I3937J0D01*
G01X775591Y676339D02*
Y561023D01*
G01X763780Y622835D02*
Y568603D01*
G01Y622835D02*
G03X755906I-3937J0D01*
G01Y653544D02*
G03X763780I3937J0D01*
G01X755906D02*
G03X751969Y657481I-3937J0D01*
G01X734843Y661418D02*
G03X738780Y657481I3937J0D01*
G01X751969D02*
X738780D01*
G01X734843Y689371D02*
X732874Y691339D01*
G01X734843Y689371D02*
Y661418D01*
G01X760014Y677788D02*
G03I-4292J0D01*
G01X775591Y676339D02*
G03X760591Y691339I-15000J0D01*
G01X751969Y665355D02*
X742717D01*
G01X763780Y653544D02*
G03X751969Y665355I-11811J0D01*
G01X742717Y691339D02*
X760591D01*
G01X742717Y665355D02*
Y691339D01*
M02*
